FILE_TYPE = MACRO_DRAWING;
SET COLOR_WIRE YELLOW;
SET COLOR_PROP MONO;
SET COLOR_DOT WHITE;
SET COLOR_ARC YELLOW;
SET COLOR_BODY GREEN;
SET COLOR_NOTE MONO;
SET PROP_DISPLAY VALUE;
SET PAGE_NUMBER P35;
FORCEADD GND..1
(-5975 1400);
FORCEPROP 3 LASTPIN (-5975 1450) SIG_NAME GND\g
J 0
(-5965 1460);
DISPLAY 0.659574 (-5965 1460);
PAINT MONO (-5965 1460);
DISPLAY INVISIBLE (-5965 1460);
FORCEPROP 1 LAST VOLTAGE 0.0V
J 0
(-6020 1357);
DISPLAY 0.340426 (-6020 1357);
PAINT SKYBLUE (-6020 1357);
DISPLAY INVISIBLE (-6020 1357);
FORCEPROP 2 LAST CDS_LIB mstr_symbols
J 0
(-5975 1400);
PAINT MONO (-5975 1400);
DISPLAY INVISIBLE (-5975 1400);
FORCEPROP 1 LAST SIZE 1B
J 0
(-5900 1350);
DISPLAY 1.170213 (-5900 1350);
PAINT AQUA (-5900 1350);
DISPLAY INVISIBLE (-5900 1350);
FORCEPROP 1 LAST PATH I2
J 0
(-5900 1400);
DISPLAY 0.872340 (-5900 1400);
PAINT AQUA (-5900 1400);
DISPLAY INVISIBLE (-5900 1400);
FORCEPROP 1 LAST BODY_TYPE PLUMBING
J 0
(-6020 1357);
DISPLAY 0.340426 (-6020 1357);
PAINT GREEN (-6020 1357);
DISPLAY INVISIBLE (-6020 1357);
FORCEPROP 1 LAST HDL_POWER GND
J 0
(-5975 1550);
DISPLAY 1.170213 (-5975 1550);
PAINT GREEN (-5975 1550);
DISPLAY INVISIBLE (-5975 1550);
FORCEADD SKX_EXT_B..15
(-4225 2625);
FORCEPROP 1 LAST LOCATION U5D1
J 0
(-4975 3875);
DISPLAY 0.617021 (-4975 3875);
PAINT AQUA (-4975 3875);
FORCEPROP 1 LAST PART_NUMBER TBD
J 0
(-4975 1425);
DISPLAY 0.617021 (-4975 1425);
PAINT BLUE (-4975 1425);
FORCEPROP 1 LAST MATERIAL IC
J 0
(-4975 3825);
DISPLAY 0.617021 (-4975 3825);
PAINT SKYBLUE (-4975 3825);
FORCEPROP 2 LASTPIN (-3425 3625) $PN CA12
J 0
(-3415 3635);
DISPLAY 0.617021 (-3415 3635);
PAINT ORANGE (-3415 3635);
FORCEPROP 2 LASTPIN (-3425 3575) $PN CB11
J 0
(-3415 3585);
DISPLAY 0.617021 (-3415 3585);
PAINT ORANGE (-3415 3585);
FORCEPROP 2 LASTPIN (-3425 3525) $PN CD11
J 0
(-3415 3535);
DISPLAY 0.617021 (-3415 3535);
PAINT ORANGE (-3415 3535);
FORCEPROP 2 LASTPIN (-3425 3475) $PN CF11
J 0
(-3415 3485);
DISPLAY 0.617021 (-3415 3485);
PAINT ORANGE (-3415 3485);
FORCEPROP 2 LASTPIN (-3425 3425) $PN CG12
J 0
(-3415 3435);
DISPLAY 0.617021 (-3415 3435);
PAINT ORANGE (-3415 3435);
FORCEPROP 2 LASTPIN (-3425 3375) $PN CH13
J 0
(-3415 3385);
DISPLAY 0.617021 (-3415 3385);
PAINT ORANGE (-3415 3385);
FORCEPROP 2 LASTPIN (-3425 3325) $PN CK13
J 0
(-3415 3335);
DISPLAY 0.617021 (-3415 3335);
PAINT ORANGE (-3415 3335);
FORCEPROP 2 LASTPIN (-3425 3275) $PN CR14
J 0
(-3415 3285);
DISPLAY 0.617021 (-3415 3285);
PAINT ORANGE (-3415 3285);
FORCEPROP 2 LASTPIN (-3425 3225) $PN CV13
J 0
(-3415 3235);
DISPLAY 0.617021 (-3415 3235);
PAINT ORANGE (-3415 3235);
FORCEPROP 2 LASTPIN (-3425 3175) $PN CW16
J 0
(-3415 3185);
DISPLAY 0.617021 (-3415 3185);
PAINT ORANGE (-3415 3185);
FORCEPROP 2 LASTPIN (-3425 3125) $PN DB15
J 0
(-3415 3135);
DISPLAY 0.617021 (-3415 3135);
PAINT ORANGE (-3415 3135);
FORCEPROP 2 LASTPIN (-3425 3075) $PN DD15
J 0
(-3415 3085);
DISPLAY 0.617021 (-3415 3085);
PAINT ORANGE (-3415 3085);
FORCEPROP 2 LASTPIN (-3425 2975) $PN DF17
J 0
(-3415 2985);
DISPLAY 0.617021 (-3415 2985);
PAINT ORANGE (-3415 2985);
FORCEPROP 2 LASTPIN (-3425 2925) $PN DH17
J 0
(-3415 2935);
DISPLAY 0.617021 (-3415 2935);
PAINT ORANGE (-3415 2935);
FORCEPROP 2 LASTPIN (-3425 2875) $PN DJ18
J 0
(-3415 2885);
DISPLAY 0.617021 (-3415 2885);
PAINT ORANGE (-3415 2885);
FORCEPROP 2 LASTPIN (-3425 2825) $PN DJ20
J 0
(-3415 2835);
DISPLAY 0.617021 (-3415 2835);
PAINT ORANGE (-3415 2835);
FORCEPROP 2 LASTPIN (-3425 2775) $PN DK19
J 0
(-3415 2785);
DISPLAY 0.617021 (-3415 2785);
PAINT ORANGE (-3415 2785);
FORCEPROP 2 LASTPIN (-3425 2725) $PN DN20
J 0
(-3415 2735);
DISPLAY 0.617021 (-3415 2735);
PAINT ORANGE (-3415 2735);
FORCEPROP 2 LASTPIN (-3425 2675) $PN DP21
J 0
(-3415 2685);
DISPLAY 0.617021 (-3415 2685);
PAINT ORANGE (-3415 2685);
FORCEPROP 2 LASTPIN (-3425 2575) $PN CC12
J 0
(-3415 2585);
DISPLAY 0.617021 (-3415 2585);
PAINT ORANGE (-3415 2585);
FORCEPROP 2 LASTPIN (-3425 2525) $PN CC10
J 0
(-3415 2535);
DISPLAY 0.617021 (-3415 2535);
PAINT ORANGE (-3415 2535);
FORCEPROP 2 LASTPIN (-3425 2475) $PN CE12
J 0
(-3415 2485);
DISPLAY 0.617021 (-3415 2485);
PAINT ORANGE (-3415 2485);
FORCEPROP 2 LASTPIN (-3425 2425) $PN CH11
J 0
(-3415 2435);
DISPLAY 0.617021 (-3415 2435);
PAINT ORANGE (-3415 2435);
FORCEPROP 2 LASTPIN (-3425 2375) $PN CF13
J 0
(-3415 2385);
DISPLAY 0.617021 (-3415 2385);
PAINT ORANGE (-3415 2385);
FORCEPROP 2 LASTPIN (-3425 2325) $PN CJ14
J 0
(-3415 2335);
DISPLAY 0.617021 (-3415 2335);
PAINT ORANGE (-3415 2335);
FORCEPROP 2 LASTPIN (-3425 2275) $PN CM13
J 0
(-3415 2285);
DISPLAY 0.617021 (-3415 2285);
PAINT ORANGE (-3415 2285);
FORCEPROP 2 LASTPIN (-3425 2225) $PN CU14
J 0
(-3415 2235);
DISPLAY 0.617021 (-3415 2235);
PAINT ORANGE (-3415 2235);
FORCEPROP 2 LASTPIN (-3425 2175) $PN CW14
J 0
(-3415 2185);
DISPLAY 0.617021 (-3415 2185);
PAINT ORANGE (-3415 2185);
FORCEPROP 2 LASTPIN (-3425 2125) $PN DA16
J 0
(-3415 2135);
DISPLAY 0.617021 (-3415 2135);
PAINT ORANGE (-3415 2135);
FORCEPROP 2 LASTPIN (-3425 2075) $PN DC16
J 0
(-3415 2085);
DISPLAY 0.617021 (-3415 2085);
PAINT ORANGE (-3415 2085);
FORCEPROP 2 LASTPIN (-3425 2025) $PN DF15
J 0
(-3415 2035);
DISPLAY 0.617021 (-3415 2035);
PAINT ORANGE (-3415 2035);
FORCEPROP 2 LASTPIN (-3425 1975) $PN DD17
J 0
(-3415 1985);
DISPLAY 0.617021 (-3415 1985);
PAINT ORANGE (-3415 1985);
FORCEPROP 2 LASTPIN (-3425 1925) $PN DG18
J 0
(-3415 1935);
DISPLAY 0.617021 (-3415 1935);
PAINT ORANGE (-3415 1935);
FORCEPROP 2 LASTPIN (-3425 1875) $PN DK17
J 0
(-3415 1885);
DISPLAY 0.617021 (-3415 1885);
PAINT ORANGE (-3415 1885);
FORCEPROP 2 LASTPIN (-3425 1825) $PN DH19
J 0
(-3415 1835);
DISPLAY 0.617021 (-3415 1835);
PAINT ORANGE (-3415 1835);
FORCEPROP 2 LASTPIN (-3425 1775) $PN DG20
J 0
(-3415 1785);
DISPLAY 0.617021 (-3415 1785);
PAINT ORANGE (-3415 1785);
FORCEPROP 2 LASTPIN (-3425 1725) $PN DL20
J 0
(-3415 1735);
DISPLAY 0.617021 (-3415 1735);
PAINT ORANGE (-3415 1735);
FORCEPROP 2 LASTPIN (-3425 1675) $PN DM21
J 0
(-3415 1685);
DISPLAY 0.617021 (-3415 1685);
PAINT ORANGE (-3415 1685);
FORCEPROP 2 LASTPIN (-3425 1625) $PN DT21
J 0
(-3415 1635);
DISPLAY 0.617021 (-3415 1635);
PAINT ORANGE (-3415 1635);
FORCEPROP 2 LASTPIN (-5025 3625) $PN CA16
J 2
(-5035 3635);
DISPLAY 0.617021 (-5035 3635);
PAINT ORANGE (-5035 3635);
FORCEPROP 2 LASTPIN (-5025 3575) $PN BY15
J 2
(-5035 3585);
DISPLAY 0.617021 (-5035 3585);
PAINT ORANGE (-5035 3585);
FORCEPROP 2 LASTPIN (-5025 3525) $PN CD17
J 2
(-5035 3535);
DISPLAY 0.617021 (-5035 3535);
PAINT ORANGE (-5035 3535);
FORCEPROP 2 LASTPIN (-5025 3475) $PN CC14
J 2
(-5035 3485);
DISPLAY 0.617021 (-5035 3485);
PAINT ORANGE (-5035 3485);
FORCEPROP 2 LASTPIN (-5025 3425) $PN CF15
J 2
(-5035 3435);
DISPLAY 0.617021 (-5035 3435);
PAINT ORANGE (-5035 3435);
FORCEPROP 2 LASTPIN (-5025 3375) $PN CG16
J 2
(-5035 3385);
DISPLAY 0.617021 (-5035 3385);
PAINT ORANGE (-5035 3385);
FORCEPROP 2 LASTPIN (-5025 3325) $PN CK17
J 2
(-5035 3335);
DISPLAY 0.617021 (-5035 3335);
PAINT ORANGE (-5035 3335);
FORCEPROP 2 LASTPIN (-5025 3275) $PN CJ16
J 2
(-5035 3285);
DISPLAY 0.617021 (-5035 3285);
PAINT ORANGE (-5035 3285);
FORCEPROP 2 LASTPIN (-5025 3225) $PN CM21
J 2
(-5035 3235);
DISPLAY 0.617021 (-5035 3235);
PAINT ORANGE (-5035 3235);
FORCEPROP 2 LASTPIN (-5025 3175) $PN CP19
J 2
(-5035 3185);
DISPLAY 0.617021 (-5035 3185);
PAINT ORANGE (-5035 3185);
FORCEPROP 2 LASTPIN (-5025 3125) $PN CN18
J 2
(-5035 3135);
DISPLAY 0.617021 (-5035 3135);
PAINT ORANGE (-5035 3135);
FORCEPROP 2 LASTPIN (-5025 3075) $PN CR20
J 2
(-5035 3085);
DISPLAY 0.617021 (-5035 3085);
PAINT ORANGE (-5035 3085);
FORCEPROP 2 LASTPIN (-5025 3025) $PN CW18
J 2
(-5035 3035);
DISPLAY 0.617021 (-5035 3035);
PAINT ORANGE (-5035 3035);
FORCEPROP 2 LASTPIN (-5025 2975) $PN CU20
J 2
(-5035 2985);
DISPLAY 0.617021 (-5035 2985);
PAINT ORANGE (-5035 2985);
FORCEPROP 2 LASTPIN (-5025 2825) $PN DC20
J 2
(-5035 2835);
DISPLAY 0.617021 (-5035 2835);
PAINT ORANGE (-5035 2835);
FORCEPROP 2 LASTPIN (-5025 2775) $PN DA22
J 2
(-5035 2785);
DISPLAY 0.617021 (-5035 2785);
PAINT ORANGE (-5035 2785);
FORCEPROP 2 LASTPIN (-5025 2725) $PN DD21
J 2
(-5035 2735);
DISPLAY 0.617021 (-5035 2735);
PAINT ORANGE (-5035 2735);
FORCEPROP 2 LASTPIN (-5025 2675) $PN DG22
J 2
(-5035 2685);
DISPLAY 0.617021 (-5035 2685);
PAINT ORANGE (-5035 2685);
FORCEPROP 2 LASTPIN (-5025 2575) $PN BY17
J 2
(-5035 2585);
DISPLAY 0.617021 (-5035 2585);
PAINT ORANGE (-5035 2585);
FORCEPROP 2 LASTPIN (-5025 2525) $PN CB15
J 2
(-5035 2535);
DISPLAY 0.617021 (-5035 2535);
PAINT ORANGE (-5035 2535);
FORCEPROP 2 LASTPIN (-5025 2475) $PN CF17
J 2
(-5035 2485);
DISPLAY 0.617021 (-5035 2485);
PAINT ORANGE (-5035 2485);
FORCEPROP 2 LASTPIN (-5025 2425) $PN CD15
J 2
(-5035 2435);
DISPLAY 0.617021 (-5035 2435);
PAINT ORANGE (-5035 2435);
FORCEPROP 2 LASTPIN (-5025 2375) $PN CE16
J 2
(-5035 2385);
DISPLAY 0.617021 (-5035 2385);
PAINT ORANGE (-5035 2385);
FORCEPROP 2 LASTPIN (-5025 2325) $PN CH17
J 2
(-5035 2335);
DISPLAY 0.617021 (-5035 2335);
PAINT ORANGE (-5035 2335);
FORCEPROP 2 LASTPIN (-5025 2275) $PN CJ18
J 2
(-5035 2285);
DISPLAY 0.617021 (-5035 2285);
PAINT ORANGE (-5035 2285);
FORCEPROP 2 LASTPIN (-5025 2225) $PN CL16
J 2
(-5035 2235);
DISPLAY 0.617021 (-5035 2235);
PAINT ORANGE (-5035 2235);
FORCEPROP 2 LASTPIN (-5025 2175) $PN CP21
J 2
(-5035 2185);
DISPLAY 0.617021 (-5035 2185);
PAINT ORANGE (-5035 2185);
FORCEPROP 2 LASTPIN (-5025 2125) $PN CN20
J 2
(-5035 2135);
DISPLAY 0.617021 (-5035 2135);
PAINT ORANGE (-5035 2135);
FORCEPROP 2 LASTPIN (-5025 2075) $PN CR18
J 2
(-5035 2085);
DISPLAY 0.617021 (-5035 2085);
PAINT ORANGE (-5035 2085);
FORCEPROP 2 LASTPIN (-5025 2025) $PN CT21
J 2
(-5035 2035);
DISPLAY 0.617021 (-5035 2035);
PAINT ORANGE (-5035 2035);
FORCEPROP 2 LASTPIN (-5025 1975) $PN CV19
J 2
(-5035 1985);
DISPLAY 0.617021 (-5035 1985);
PAINT ORANGE (-5035 1985);
FORCEPROP 2 LASTPIN (-5025 1925) $PN CW20
J 2
(-5035 1935);
DISPLAY 0.617021 (-5035 1935);
PAINT ORANGE (-5035 1935);
FORCEPROP 2 LASTPIN (-5025 1875) $PN DA20
J 2
(-5035 1885);
DISPLAY 0.617021 (-5035 1885);
PAINT ORANGE (-5035 1885);
FORCEPROP 2 LASTPIN (-5025 1825) $PN DD19
J 2
(-5035 1835);
DISPLAY 0.617021 (-5035 1835);
PAINT ORANGE (-5035 1835);
FORCEPROP 2 LASTPIN (-5025 1775) $PN DB21
J 2
(-5035 1785);
DISPLAY 0.617021 (-5035 1785);
PAINT ORANGE (-5035 1785);
FORCEPROP 2 LASTPIN (-5025 1725) $PN DC22
J 2
(-5035 1735);
DISPLAY 0.617021 (-5035 1735);
PAINT ORANGE (-5035 1735);
FORCEPROP 2 LASTPIN (-5025 1675) $PN DE22
J 2
(-5035 1685);
DISPLAY 0.617021 (-5035 1685);
PAINT ORANGE (-5035 1685);
FORCEPROP 2 LASTPIN (-5025 1625) $PN DF23
J 2
(-5035 1635);
DISPLAY 0.617021 (-5035 1635);
PAINT ORANGE (-5035 1635);
FORCEPROP 2 LASTPIN (-5025 2925) $PN CY19
J 2
(-5035 2935);
DISPLAY 0.617021 (-5035 2935);
PAINT ORANGE (-5035 2935);
FORCEPROP 2 LASTPIN (-5025 2875) $PN DB19
J 2
(-5035 2885);
DISPLAY 0.617021 (-5035 2885);
PAINT ORANGE (-5035 2885);
FORCEPROP 2 LASTPIN (-3425 3025) $PN DE16
J 0
(-3415 3035);
DISPLAY 0.617021 (-3415 3035);
PAINT ORANGE (-3415 3035);
FORCEPROP 1 LAST PACK_TYPE BGA1
J 0
(-4975 3925);
PAINT SKYBLUE (-4975 3925);
DISPLAY INVISIBLE (-4975 3925);
FORCEPROP 2 LAST CDS_LIB chpset_lib
J 0
(-4225 2625);
PAINT ORANGE (-4225 2625);
DISPLAY INVISIBLE (-4225 2625);
FORCEPROP 2 LAST SEC_TYPE BGA1
J 0
(-4975 3925);
DISPLAY 1.021277 (-4975 3925);
PAINT ORANGE (-4975 3925);
DISPLAY INVISIBLE (-4975 3925);
FORCEPROP 2 LAST SEC 15
J 0
(-4975 3925);
DISPLAY 0.680851 (-4975 3925);
PAINT MONO (-4975 3925);
DISPLAY INVISIBLE (-4975 3925);
FORCEPROP 2 LAST CDS_LOCATION U5D1
J 0
(-4975 3875);
DISPLAY 0.617021 (-4975 3875);
PAINT AQUA (-4975 3875);
DISPLAY INVISIBLE (-4975 3875);
FORCEPROP 1 LAST PATH I3
J 0
(-4225 3825);
PAINT GREEN (-4225 3825);
DISPLAY INVISIBLE (-4225 3825);
FORCEPROP 0 LAST ROOM CPU0
J 0
(-4975 3975);
DISPLAY 1.021277 (-4975 3975);
PAINT ORANGE (-4975 3975);
DISPLAY INVISIBLE (-4975 3975);
FORCEADD DESIGN_NOTE..1
(-4850 1325);
FORCEPROP 0 LAST L1 CPU SYMBOLS 1-30 ARE PRELIMINARY AND SUBJECT TO CHANGE
J 0
(-5050 1200);
DISPLAY 1.021277 (-5050 1200);
PAINT ORANGE (-5050 1200);
FORCEPROP 2 LAST CDS_LIB mstr_symbols
J 0
(-4850 1325);
PAINT ORANGE (-4850 1325);
DISPLAY INVISIBLE (-4850 1325);
FORCEPROP 1 LAST COMMENT_BODY TRUE
J 0
(-4825 1425);
DISPLAY 0.978723 (-4825 1425);
PAINT ORANGE (-4825 1425);
DISPLAY INVISIBLE (-4825 1425);
FORCEADD INTEL_CORP_BPAGE..1
(0 0);
FORCEPROP 1 LAST CDS_CON_LAST_MODIFIED Fri Jun 16 17:48:13 2017
J 0
(-1425 325);
DISPLAY 1.340426 (-1425 325);
PAINT GREEN (-1425 325);
DISPLAY INVISIBLE (-1425 325);
FORCEPROP 1 LAST CUSTOM_TXT_CDS <CURRENT_DESIGN_SHEET> OF <TOTAL_DESIGN_SHEETS>
J 0
(-500 25);
PAINT ORANGE (-500 25);
FORCEPROP 1 LAST CUSTOM_TXT_CDS <CON_LAST_MODIFIED>
J 0
(-4000 100);
PAINT ORANGE (-4000 100);
FORCEPROP 2 LAST CUSTOM_TXT_CDS <XR_PAGE_TITLE>
J 0
(-7890 5250);
DISPLAY 0.638298 (-7890 5250);
PAINT PINK (-7890 5250);
DISPLAY INVISIBLE (-7890 5250);
FORCEPROP 1 LAST SCH_TITLE SKYLAKE - SKT0 - 15 OF 21
J 0
(-7950 50);
DISPLAY 1.212766 (-7950 50);
PAINT GREEN (-7950 50);
FORCEPROP 2 LAST CDS_LIB mstr_symbols
J 0
(0 0);
PAINT ORANGE (0 0);
DISPLAY INVISIBLE (0 0);
FORCEPROP 2 LAST PAGE_BORDER TRUE
J 0
(-7890 5250);
DISPLAY 0.851064 (-7890 5250);
PAINT PINK (-7890 5250);
DISPLAY INVISIBLE (-7890 5250);
FORCEPROP 1 LAST COMMENT_BODY TRUE
J 0
(12 12);
DISPLAY 0.638298 (12 12);
PAINT GREEN (12 12);
DISPLAY INVISIBLE (12 12);
FORCEPROP 2 LAST CDS_XR_PAGE_TITLE CR-35 : @BASEBOARD_FAB2_LIB.BASEBOARD_FAB2(SCH_1):PAGE35
J 0
(-7890 5250);
DISPLAY 0.638298 (-7890 5250);
PAINT PINK (-7890 5250);
DISPLAY INVISIBLE (-7890 5250);
WIRE 16 -1 (-5975 1625)(-5975 1450);
WIRE 16 -1 (-5975 1675)(-5975 1625);
WIRE 16 -1 (-5025 1625)(-5975 1625);
WIRE 16 -1 (-5975 1725)(-5975 1675);
WIRE 16 -1 (-5025 1675)(-5975 1675);
WIRE 16 -1 (-5975 1775)(-5975 1725);
WIRE 16 -1 (-5025 1725)(-5975 1725);
WIRE 16 -1 (-5975 1825)(-5975 1775);
WIRE 16 -1 (-5025 1775)(-5975 1775);
WIRE 16 -1 (-5975 1875)(-5975 1825);
WIRE 16 -1 (-5025 1825)(-5975 1825);
WIRE 16 -1 (-5975 1925)(-5975 1875);
WIRE 16 -1 (-5025 1875)(-5975 1875);
WIRE 16 -1 (-5975 1975)(-5975 1925);
WIRE 16 -1 (-5025 1925)(-5975 1925);
WIRE 16 -1 (-5975 2025)(-5975 1975);
WIRE 16 -1 (-5025 1975)(-5975 1975);
WIRE 16 -1 (-5975 2075)(-5975 2025);
WIRE 16 -1 (-5025 2025)(-5975 2025);
WIRE 16 -1 (-5975 2125)(-5975 2075);
WIRE 16 -1 (-5025 2075)(-5975 2075);
WIRE 16 -1 (-5975 2175)(-5975 2125);
WIRE 16 -1 (-5025 2125)(-5975 2125);
WIRE 16 -1 (-5975 2225)(-5975 2175);
WIRE 16 -1 (-5025 2175)(-5975 2175);
WIRE 16 -1 (-5975 2275)(-5975 2225);
WIRE 16 -1 (-5025 2225)(-5975 2225);
WIRE 16 -1 (-5975 2325)(-5975 2275);
WIRE 16 -1 (-5025 2275)(-5975 2275);
WIRE 16 -1 (-5975 2375)(-5975 2325);
WIRE 16 -1 (-5025 2325)(-5975 2325);
WIRE 16 -1 (-5975 2425)(-5975 2375);
WIRE 16 -1 (-5025 2375)(-5975 2375);
WIRE 16 -1 (-5975 2475)(-5975 2425);
WIRE 16 -1 (-5025 2425)(-5975 2425);
WIRE 16 -1 (-5975 2525)(-5975 2475);
WIRE 16 -1 (-5025 2475)(-5975 2475);
WIRE 16 -1 (-5975 2575)(-5975 2525);
WIRE 16 -1 (-5025 2525)(-5975 2525);
WIRE 16 -1 (-5975 2675)(-5975 2575);
WIRE 16 -1 (-5025 2575)(-5975 2575);
WIRE 16 -1 (-5975 2725)(-5975 2675);
WIRE 16 -1 (-5025 2675)(-5975 2675);
WIRE 16 -1 (-5975 2775)(-5975 2725);
WIRE 16 -1 (-5025 2725)(-5975 2725);
WIRE 16 -1 (-5975 2825)(-5975 2775);
WIRE 16 -1 (-5025 2775)(-5975 2775);
WIRE 16 -1 (-5975 2875)(-5975 2825);
WIRE 16 -1 (-5025 2825)(-5975 2825);
WIRE 16 -1 (-5975 2925)(-5975 2875);
WIRE 16 -1 (-5025 2875)(-5975 2875);
WIRE 16 -1 (-5975 2975)(-5975 2925);
WIRE 16 -1 (-5025 2925)(-5975 2925);
WIRE 16 -1 (-5975 3025)(-5975 2975);
WIRE 16 -1 (-5025 2975)(-5975 2975);
WIRE 16 -1 (-5975 3075)(-5975 3025);
WIRE 16 -1 (-5025 3025)(-5975 3025);
WIRE 16 -1 (-5975 3125)(-5975 3075);
WIRE 16 -1 (-5025 3075)(-5975 3075);
WIRE 16 -1 (-5975 3175)(-5975 3125);
WIRE 16 -1 (-5025 3125)(-5975 3125);
WIRE 16 -1 (-5975 3225)(-5975 3175);
WIRE 16 -1 (-5025 3175)(-5975 3175);
WIRE 16 -1 (-5975 3275)(-5975 3225);
WIRE 16 -1 (-5025 3225)(-5975 3225);
WIRE 16 -1 (-5975 3325)(-5975 3275);
WIRE 16 -1 (-5025 3275)(-5975 3275);
WIRE 16 -1 (-5975 3375)(-5975 3325);
WIRE 16 -1 (-5025 3325)(-5975 3325);
WIRE 16 -1 (-5975 3425)(-5975 3375);
WIRE 16 -1 (-5025 3375)(-5975 3375);
WIRE 16 -1 (-5975 3475)(-5975 3425);
WIRE 16 -1 (-5025 3425)(-5975 3425);
WIRE 16 -1 (-5975 3525)(-5975 3475);
WIRE 16 -1 (-5025 3475)(-5975 3475);
WIRE 16 -1 (-5975 3575)(-5975 3525);
WIRE 16 -1 (-5025 3525)(-5975 3525);
WIRE 16 -1 (-5975 3625)(-5975 3575);
WIRE 16 -1 (-5025 3575)(-5975 3575);
WIRE 16 -1 (-5025 3625)(-5975 3625);
WIRE 16 -1 (-2475 2575)(-3425 2575);
FORCEPROP 0 LAST SIG_NAME TP_CPU0_UPI2_RSVD_DT21
J 0
(-3075 2585);
DISPLAY 0.617021 (-3075 2585);
PAINT ORANGE (-3075 2585);
FORCEPROP 2 LASTPROP $XRERR UNIQUE?
J 0
(-2445 2575);
DISPLAY 0.638298 (-2445 2575);
PAINT MONO (-2445 2575);
DISPLAY INVISIBLE (-2445 2575);
WIRE 16 -1 (-2475 2525)(-3425 2525);
FORCEPROP 0 LAST SIG_NAME TP_CPU0_UPI2_RSVD_DM21
J 0
(-3075 2535);
DISPLAY 0.617021 (-3075 2535);
PAINT ORANGE (-3075 2535);
FORCEPROP 2 LASTPROP $XRERR UNIQUE?
J 0
(-2445 2525);
DISPLAY 0.638298 (-2445 2525);
PAINT MONO (-2445 2525);
DISPLAY INVISIBLE (-2445 2525);
WIRE 16 -1 (-2475 2475)(-3425 2475);
FORCEPROP 0 LAST SIG_NAME TP_CPU0_UPI2_RSVD_DL20
J 0
(-3075 2485);
DISPLAY 0.617021 (-3075 2485);
PAINT ORANGE (-3075 2485);
FORCEPROP 2 LASTPROP $XRERR UNIQUE?
J 0
(-2445 2475);
DISPLAY 0.638298 (-2445 2475);
PAINT MONO (-2445 2475);
DISPLAY INVISIBLE (-2445 2475);
WIRE 16 -1 (-2475 2425)(-3425 2425);
FORCEPROP 0 LAST SIG_NAME TP_CPU0_UPI2_RSVD_DG20
J 0
(-3075 2435);
DISPLAY 0.617021 (-3075 2435);
PAINT ORANGE (-3075 2435);
FORCEPROP 2 LASTPROP $XRERR UNIQUE?
J 0
(-2445 2425);
DISPLAY 0.638298 (-2445 2425);
PAINT MONO (-2445 2425);
DISPLAY INVISIBLE (-2445 2425);
WIRE 16 -1 (-2475 2375)(-3425 2375);
FORCEPROP 0 LAST SIG_NAME TP_CPU0_UPI2_RSVD_DH19
J 0
(-3075 2385);
DISPLAY 0.617021 (-3075 2385);
PAINT ORANGE (-3075 2385);
FORCEPROP 2 LASTPROP $XRERR UNIQUE?
J 0
(-2445 2375);
DISPLAY 0.638298 (-2445 2375);
PAINT MONO (-2445 2375);
DISPLAY INVISIBLE (-2445 2375);
WIRE 16 -1 (-2475 2325)(-3425 2325);
FORCEPROP 0 LAST SIG_NAME TP_CPU0_UPI2_RSVD_DK17
J 0
(-3075 2335);
DISPLAY 0.617021 (-3075 2335);
PAINT ORANGE (-3075 2335);
FORCEPROP 2 LASTPROP $XRERR UNIQUE?
J 0
(-2445 2325);
DISPLAY 0.638298 (-2445 2325);
PAINT MONO (-2445 2325);
DISPLAY INVISIBLE (-2445 2325);
WIRE 16 -1 (-2475 2275)(-3425 2275);
FORCEPROP 0 LAST SIG_NAME TP_CPU0_UPI2_RSVD_DG18
J 0
(-3075 2285);
DISPLAY 0.617021 (-3075 2285);
PAINT ORANGE (-3075 2285);
FORCEPROP 2 LASTPROP $XRERR UNIQUE?
J 0
(-2445 2275);
DISPLAY 0.638298 (-2445 2275);
PAINT MONO (-2445 2275);
DISPLAY INVISIBLE (-2445 2275);
WIRE 16 -1 (-2475 2225)(-3425 2225);
FORCEPROP 0 LAST SIG_NAME TP_CPU0_UPI2_RSVD_DD17
J 0
(-3075 2235);
DISPLAY 0.617021 (-3075 2235);
PAINT ORANGE (-3075 2235);
FORCEPROP 2 LASTPROP $XRERR UNIQUE?
J 0
(-2445 2225);
DISPLAY 0.638298 (-2445 2225);
PAINT MONO (-2445 2225);
DISPLAY INVISIBLE (-2445 2225);
WIRE 16 -1 (-2475 2175)(-3425 2175);
FORCEPROP 0 LAST SIG_NAME TP_CPU0_UPI2_RSVD_DF15
J 0
(-3075 2185);
DISPLAY 0.617021 (-3075 2185);
PAINT ORANGE (-3075 2185);
FORCEPROP 2 LASTPROP $XRERR UNIQUE?
J 0
(-2445 2175);
DISPLAY 0.638298 (-2445 2175);
PAINT MONO (-2445 2175);
DISPLAY INVISIBLE (-2445 2175);
WIRE 16 -1 (-2475 2125)(-3425 2125);
FORCEPROP 0 LAST SIG_NAME TP_CPU0_UPI2_RSVD_DC16
J 0
(-3075 2135);
DISPLAY 0.617021 (-3075 2135);
PAINT ORANGE (-3075 2135);
FORCEPROP 2 LASTPROP $XRERR UNIQUE?
J 0
(-2445 2125);
DISPLAY 0.638298 (-2445 2125);
PAINT MONO (-2445 2125);
DISPLAY INVISIBLE (-2445 2125);
WIRE 16 -1 (-2475 2075)(-3425 2075);
FORCEPROP 0 LAST SIG_NAME TP_CPU0_UPI2_RSVD_DA16
J 0
(-3075 2085);
DISPLAY 0.617021 (-3075 2085);
PAINT ORANGE (-3075 2085);
FORCEPROP 2 LASTPROP $XRERR UNIQUE?
J 0
(-2445 2075);
DISPLAY 0.638298 (-2445 2075);
PAINT MONO (-2445 2075);
DISPLAY INVISIBLE (-2445 2075);
WIRE 16 -1 (-2475 3625)(-3425 3625);
FORCEPROP 0 LAST SIG_NAME TP_CPU0_UPI2_RSVD_DP21
J 0
(-3075 3635);
DISPLAY 0.617021 (-3075 3635);
PAINT ORANGE (-3075 3635);
FORCEPROP 2 LASTPROP $XRERR UNIQUE?
J 0
(-2445 3625);
DISPLAY 0.638298 (-2445 3625);
PAINT MONO (-2445 3625);
DISPLAY INVISIBLE (-2445 3625);
WIRE 16 -1 (-2475 3575)(-3425 3575);
FORCEPROP 0 LAST SIG_NAME TP_CPU0_UPI2_RSVD_DN20
J 0
(-3075 3585);
DISPLAY 0.617021 (-3075 3585);
PAINT ORANGE (-3075 3585);
FORCEPROP 2 LASTPROP $XRERR UNIQUE?
J 0
(-2445 3575);
DISPLAY 0.638298 (-2445 3575);
PAINT MONO (-2445 3575);
DISPLAY INVISIBLE (-2445 3575);
WIRE 16 -1 (-2475 3525)(-3425 3525);
FORCEPROP 0 LAST SIG_NAME TP_CPU0_UPI2_RSVD_DK19
J 0
(-3075 3535);
DISPLAY 0.617021 (-3075 3535);
PAINT ORANGE (-3075 3535);
FORCEPROP 2 LASTPROP $XRERR UNIQUE?
J 0
(-2445 3525);
DISPLAY 0.638298 (-2445 3525);
PAINT MONO (-2445 3525);
DISPLAY INVISIBLE (-2445 3525);
WIRE 16 -1 (-2475 3475)(-3425 3475);
FORCEPROP 0 LAST SIG_NAME TP_CPU0_UPI2_RSVD_DJ20
J 0
(-3075 3485);
DISPLAY 0.617021 (-3075 3485);
PAINT ORANGE (-3075 3485);
FORCEPROP 2 LASTPROP $XRERR UNIQUE?
J 0
(-2445 3475);
DISPLAY 0.638298 (-2445 3475);
PAINT MONO (-2445 3475);
DISPLAY INVISIBLE (-2445 3475);
WIRE 16 -1 (-2475 3425)(-3425 3425);
FORCEPROP 0 LAST SIG_NAME TP_CPU0_UPI2_RSVD_DJ18
J 0
(-3075 3435);
DISPLAY 0.617021 (-3075 3435);
PAINT ORANGE (-3075 3435);
FORCEPROP 2 LASTPROP $XRERR UNIQUE?
J 0
(-2445 3425);
DISPLAY 0.638298 (-2445 3425);
PAINT MONO (-2445 3425);
DISPLAY INVISIBLE (-2445 3425);
WIRE 16 -1 (-2475 3375)(-3425 3375);
FORCEPROP 0 LAST SIG_NAME TP_CPU0_UPI2_RSVD_DH17
J 0
(-3075 3385);
DISPLAY 0.617021 (-3075 3385);
PAINT ORANGE (-3075 3385);
FORCEPROP 2 LASTPROP $XRERR UNIQUE?
J 0
(-2445 3375);
DISPLAY 0.638298 (-2445 3375);
PAINT MONO (-2445 3375);
DISPLAY INVISIBLE (-2445 3375);
WIRE 16 -1 (-2475 3325)(-3425 3325);
FORCEPROP 0 LAST SIG_NAME TP_CPU0_UPI2_RSVD_DF17
J 0
(-3075 3335);
DISPLAY 0.617021 (-3075 3335);
PAINT ORANGE (-3075 3335);
FORCEPROP 2 LASTPROP $XRERR UNIQUE?
J 0
(-2445 3325);
DISPLAY 0.638298 (-2445 3325);
PAINT MONO (-2445 3325);
DISPLAY INVISIBLE (-2445 3325);
WIRE 16 -1 (-2475 3275)(-3425 3275);
FORCEPROP 0 LAST SIG_NAME TP_CPU0_UPI2_RSVD_DE16
J 0
(-3075 3285);
DISPLAY 0.617021 (-3075 3285);
PAINT ORANGE (-3075 3285);
FORCEPROP 2 LASTPROP $XRERR UNIQUE?
J 0
(-2445 3275);
DISPLAY 0.638298 (-2445 3275);
PAINT MONO (-2445 3275);
DISPLAY INVISIBLE (-2445 3275);
WIRE 16 -1 (-2475 3225)(-3425 3225);
FORCEPROP 0 LAST SIG_NAME TP_CPU0_UPI2_RSVD_DD15
J 0
(-3075 3235);
DISPLAY 0.617021 (-3075 3235);
PAINT ORANGE (-3075 3235);
FORCEPROP 2 LASTPROP $XRERR UNIQUE?
J 0
(-2445 3225);
DISPLAY 0.638298 (-2445 3225);
PAINT MONO (-2445 3225);
DISPLAY INVISIBLE (-2445 3225);
WIRE 16 -1 (-2475 3175)(-3425 3175);
FORCEPROP 0 LAST SIG_NAME TP_CPU0_UPI2_RSVD_DB15
J 0
(-3075 3185);
DISPLAY 0.617021 (-3075 3185);
PAINT ORANGE (-3075 3185);
FORCEPROP 2 LASTPROP $XRERR UNIQUE?
J 0
(-2445 3175);
DISPLAY 0.638298 (-2445 3175);
PAINT MONO (-2445 3175);
DISPLAY INVISIBLE (-2445 3175);
WIRE 16 -1 (-2475 3125)(-3425 3125);
FORCEPROP 0 LAST SIG_NAME TP_CPU0_UPI2_RSVD_CW16
J 0
(-3075 3135);
DISPLAY 0.617021 (-3075 3135);
PAINT ORANGE (-3075 3135);
FORCEPROP 2 LASTPROP $XRERR UNIQUE?
J 0
(-2445 3125);
DISPLAY 0.638298 (-2445 3125);
PAINT MONO (-2445 3125);
DISPLAY INVISIBLE (-2445 3125);
WIRE 16 -1 (-2475 3025)(-3425 3025);
FORCEPROP 0 LAST SIG_NAME TP_CPU0_UPI2_RSVD_CR14
J 0
(-3075 3035);
DISPLAY 0.617021 (-3075 3035);
PAINT ORANGE (-3075 3035);
FORCEPROP 2 LASTPROP $XRERR UNIQUE?
J 0
(-2445 3025);
DISPLAY 0.638298 (-2445 3025);
PAINT MONO (-2445 3025);
DISPLAY INVISIBLE (-2445 3025);
WIRE 16 -1 (-2475 2975)(-3425 2975);
FORCEPROP 0 LAST SIG_NAME TP_CPU0_UPI2_RSVD_CK13
J 0
(-3075 2985);
DISPLAY 0.617021 (-3075 2985);
PAINT ORANGE (-3075 2985);
FORCEPROP 2 LASTPROP $XRERR UNIQUE?
J 0
(-2445 2975);
DISPLAY 0.638298 (-2445 2975);
PAINT MONO (-2445 2975);
DISPLAY INVISIBLE (-2445 2975);
WIRE 16 -1 (-2475 2925)(-3425 2925);
FORCEPROP 0 LAST SIG_NAME TP_CPU0_UPI2_RSVD_CH13
J 0
(-3075 2935);
DISPLAY 0.617021 (-3075 2935);
PAINT ORANGE (-3075 2935);
FORCEPROP 2 LASTPROP $XRERR UNIQUE?
J 0
(-2445 2925);
DISPLAY 0.638298 (-2445 2925);
PAINT MONO (-2445 2925);
DISPLAY INVISIBLE (-2445 2925);
WIRE 16 -1 (-2475 2875)(-3425 2875);
FORCEPROP 0 LAST SIG_NAME TP_CPU0_UPI2_RSVD_CG12
J 0
(-3075 2885);
DISPLAY 0.617021 (-3075 2885);
PAINT ORANGE (-3075 2885);
FORCEPROP 2 LASTPROP $XRERR UNIQUE?
J 0
(-2445 2875);
DISPLAY 0.638298 (-2445 2875);
PAINT MONO (-2445 2875);
DISPLAY INVISIBLE (-2445 2875);
WIRE 16 -1 (-2475 2775)(-3425 2775);
FORCEPROP 0 LAST SIG_NAME TP_CPU0_UPI2_RSVD_CD11
J 0
(-3075 2785);
DISPLAY 0.617021 (-3075 2785);
PAINT ORANGE (-3075 2785);
FORCEPROP 2 LASTPROP $XRERR UNIQUE?
J 0
(-2445 2775);
DISPLAY 0.638298 (-2445 2775);
PAINT MONO (-2445 2775);
DISPLAY INVISIBLE (-2445 2775);
WIRE 16 -1 (-2475 2725)(-3425 2725);
FORCEPROP 0 LAST SIG_NAME TP_CPU0_UPI2_RSVD_CB11
J 0
(-3075 2735);
DISPLAY 0.617021 (-3075 2735);
PAINT ORANGE (-3075 2735);
FORCEPROP 2 LASTPROP $XRERR UNIQUE?
J 0
(-2445 2725);
DISPLAY 0.638298 (-2445 2725);
PAINT MONO (-2445 2725);
DISPLAY INVISIBLE (-2445 2725);
WIRE 16 -1 (-2475 2675)(-3425 2675);
FORCEPROP 0 LAST SIG_NAME TP_CPU0_UPI2_RSVD_CA12
J 0
(-3075 2685);
DISPLAY 0.617021 (-3075 2685);
PAINT ORANGE (-3075 2685);
FORCEPROP 2 LASTPROP $XRERR UNIQUE?
J 0
(-2445 2675);
DISPLAY 0.638298 (-2445 2675);
PAINT MONO (-2445 2675);
DISPLAY INVISIBLE (-2445 2675);
WIRE 16 -1 (-2475 2025)(-3425 2025);
FORCEPROP 0 LAST SIG_NAME TP_CPU0_UPI2_RSVD_CW14
J 0
(-3075 2035);
DISPLAY 0.617021 (-3075 2035);
PAINT ORANGE (-3075 2035);
FORCEPROP 2 LASTPROP $XRERR UNIQUE?
J 0
(-2445 2025);
DISPLAY 0.638298 (-2445 2025);
PAINT MONO (-2445 2025);
DISPLAY INVISIBLE (-2445 2025);
WIRE 16 -1 (-2475 1975)(-3425 1975);
FORCEPROP 0 LAST SIG_NAME TP_CPU0_UPI2_RSVD_CU14
J 0
(-3075 1985);
DISPLAY 0.617021 (-3075 1985);
PAINT ORANGE (-3075 1985);
FORCEPROP 2 LASTPROP $XRERR UNIQUE?
J 0
(-2445 1975);
DISPLAY 0.638298 (-2445 1975);
PAINT MONO (-2445 1975);
DISPLAY INVISIBLE (-2445 1975);
WIRE 16 -1 (-2475 1925)(-3425 1925);
FORCEPROP 0 LAST SIG_NAME TP_CPU0_UPI2_RSVD_CM13
J 0
(-3075 1935);
DISPLAY 0.617021 (-3075 1935);
PAINT ORANGE (-3075 1935);
FORCEPROP 2 LASTPROP $XRERR UNIQUE?
J 0
(-2445 1925);
DISPLAY 0.638298 (-2445 1925);
PAINT MONO (-2445 1925);
DISPLAY INVISIBLE (-2445 1925);
WIRE 16 -1 (-2475 1875)(-3425 1875);
FORCEPROP 0 LAST SIG_NAME TP_CPU0_UPI2_RSVD_CJ14
J 0
(-3075 1885);
DISPLAY 0.617021 (-3075 1885);
PAINT ORANGE (-3075 1885);
FORCEPROP 2 LASTPROP $XRERR UNIQUE?
J 0
(-2445 1875);
DISPLAY 0.638298 (-2445 1875);
PAINT MONO (-2445 1875);
DISPLAY INVISIBLE (-2445 1875);
WIRE 16 -1 (-2475 1825)(-3425 1825);
FORCEPROP 0 LAST SIG_NAME TP_CPU0_UPI2_RSVD_CF13
J 0
(-3075 1835);
DISPLAY 0.617021 (-3075 1835);
PAINT ORANGE (-3075 1835);
FORCEPROP 2 LASTPROP $XRERR UNIQUE?
J 0
(-2445 1825);
DISPLAY 0.638298 (-2445 1825);
PAINT MONO (-2445 1825);
DISPLAY INVISIBLE (-2445 1825);
WIRE 16 -1 (-2475 1775)(-3425 1775);
FORCEPROP 0 LAST SIG_NAME TP_CPU0_UPI2_RSVD_CH11
J 0
(-3075 1785);
DISPLAY 0.617021 (-3075 1785);
PAINT ORANGE (-3075 1785);
FORCEPROP 2 LASTPROP $XRERR UNIQUE?
J 0
(-2445 1775);
DISPLAY 0.638298 (-2445 1775);
PAINT MONO (-2445 1775);
DISPLAY INVISIBLE (-2445 1775);
WIRE 16 -1 (-2475 1725)(-3425 1725);
FORCEPROP 0 LAST SIG_NAME TP_CPU0_UPI2_RSVD_CE12
J 0
(-3075 1735);
DISPLAY 0.617021 (-3075 1735);
PAINT ORANGE (-3075 1735);
FORCEPROP 2 LASTPROP $XRERR UNIQUE?
J 0
(-2445 1725);
DISPLAY 0.638298 (-2445 1725);
PAINT MONO (-2445 1725);
DISPLAY INVISIBLE (-2445 1725);
WIRE 16 -1 (-2475 1675)(-3425 1675);
FORCEPROP 0 LAST SIG_NAME TP_CPU0_UPI2_RSVD_CC10
J 0
(-3075 1685);
DISPLAY 0.617021 (-3075 1685);
PAINT ORANGE (-3075 1685);
FORCEPROP 2 LASTPROP $XRERR UNIQUE?
J 0
(-2445 1675);
DISPLAY 0.638298 (-2445 1675);
PAINT MONO (-2445 1675);
DISPLAY INVISIBLE (-2445 1675);
WIRE 16 -1 (-2475 1625)(-3425 1625);
FORCEPROP 0 LAST SIG_NAME TP_CPU0_UPI2_RSVD_CC12
J 0
(-3075 1635);
DISPLAY 0.617021 (-3075 1635);
PAINT ORANGE (-3075 1635);
FORCEPROP 2 LASTPROP $XRERR UNIQUE?
J 0
(-2445 1625);
DISPLAY 0.638298 (-2445 1625);
PAINT MONO (-2445 1625);
DISPLAY INVISIBLE (-2445 1625);
WIRE 16 -1 (-2475 2825)(-3425 2825);
FORCEPROP 0 LAST SIG_NAME TP_CPU0_UPI2_RSVD_CF11
J 0
(-3075 2835);
DISPLAY 0.617021 (-3075 2835);
PAINT ORANGE (-3075 2835);
FORCEPROP 2 LASTPROP $XRERR UNIQUE?
J 0
(-2445 2825);
DISPLAY 0.638298 (-2445 2825);
PAINT MONO (-2445 2825);
DISPLAY INVISIBLE (-2445 2825);
WIRE 16 -1 (-2475 3075)(-3425 3075);
FORCEPROP 0 LAST SIG_NAME TP_CPU0_UPI2_RSVD_CV13
J 0
(-3075 3085);
DISPLAY 0.617021 (-3075 3085);
PAINT ORANGE (-3075 3085);
FORCEPROP 2 LASTPROP $XRERR UNIQUE?
J 0
(-2445 3075);
DISPLAY 0.638298 (-2445 3075);
PAINT MONO (-2445 3075);
DISPLAY INVISIBLE (-2445 3075);
DOT 1 (-5975 3575);
DOT 1 (-5975 3525);
DOT 1 (-5975 3475);
DOT 1 (-5975 3425);
DOT 1 (-5975 3375);
DOT 1 (-5975 3325);
DOT 1 (-5975 3275);
DOT 1 (-5975 3225);
DOT 1 (-5975 3175);
DOT 1 (-5975 3125);
DOT 1 (-5975 3075);
DOT 1 (-5975 3025);
DOT 1 (-5975 2975);
DOT 1 (-5975 2925);
DOT 1 (-5975 2875);
DOT 1 (-5975 2825);
DOT 1 (-5975 2775);
DOT 1 (-5975 2725);
DOT 1 (-5975 2675);
DOT 1 (-5975 2575);
DOT 1 (-5975 2525);
DOT 1 (-5975 2475);
DOT 1 (-5975 2425);
DOT 1 (-5975 2375);
DOT 1 (-5975 2325);
DOT 1 (-5975 2275);
DOT 1 (-5975 2225);
DOT 1 (-5975 2175);
DOT 1 (-5975 2125);
DOT 1 (-5975 2075);
DOT 1 (-5975 2025);
DOT 1 (-5975 1975);
DOT 1 (-5975 1925);
DOT 1 (-5975 1875);
DOT 1 (-5975 1825);
DOT 1 (-5975 1775);
DOT 1 (-5975 1725);
DOT 1 (-5975 1675);
DOT 1 (-5975 1625);
FORCENOTE
SKYLAKE - SKT0 - 15 OF 21
(-1575 175) 0;
DISPLAY LEFT (-1575 175);
DISPLAY 1.021277 (-1575 175);
PAINT RED (-1575 175);
FORCENOTE
BOM_COST=PROC_SOCKET
(-7925 250) 0;
DISPLAY LEFT (-7925 250);
DISPLAY 1.723404 (-7925 250);
PAINT PURPLE (-7925 250);
FORCENOTE
ROOM=CPU0
(-7925 375) 0;
DISPLAY LEFT (-7925 375);
DISPLAY 1.723404 (-7925 375);
PAINT PURPLE (-7925 375);
QUIT
